FILE_TYPE = MACRO_DRAWING;
SET COLOR_WIRE YELLOW;
SET COLOR_PROP ORANGE;
SET COLOR_DOT WHITE;
SET COLOR_ARC YELLOW;
SET COLOR_BODY GREEN;
SET COLOR_NOTE PURPLE;
SET PROP_DISPLAY VALUE;
SET PAGE_NUMBER P403;
FORCEADD QUANTA_TITLE_BLOCK_C..1
(0 0);
FORCEPROP 1 LAST CUSTOM_TXT_CDS <NAME_2>
J 0
(-3175 50);
FORCEPROP 1 LAST CUSTOM_TXT_CDS <NAME_1>
J 0
(-3175 175);
FORCEPROP 1 LAST CUSTOM_TXT_CDS <Q_NUMBER>
J 0
(-1403 103);
DISPLAY 1.212766 (-1403 103);
FORCEPROP 1 LAST CUSTOM_TXT_CDS <Q_PROJ>
J 0
(-2382 102);
DISPLAY 1.212766 (-2382 102);
FORCEPROP 1 LAST CUSTOM_TXT_CDS <Q_REV>
J 0
(-184 103);
DISPLAY 1.212766 (-184 103);
FORCEPROP 1 LAST CUSTOM_TXT_CDS <CON_LAST_MODIFIED>
J 0
(-1885 15);
DISPLAY 0.978723 (-1885 15);
FORCEPROP 1 LAST CUSTOM_TXT_CDS <CON_PAGE_NUM> OF <CON_TOTAL_PAGES>
J 0
(-446 18);
DISPLAY 0.978723 (-446 18);
FORCEPROP 1 LAST Q_TITLE BLANK
J 0
(-9366 26);
DISPLAY 2.446809 (-9366 26);
PAINT GREEN (-9366 26);
FORCEPROP 2 LAST CDS_LIB pure_quanta
J 0
(0 0);
DISPLAY INVISIBLE (0 0);
FORCEPROP 1 LAST CDS_LMAN_SYM_OUTLINE -9475,6775,100,-125
J 0
(0 0);
DISPLAY 0.468085 (0 0);
PAINT GREEN (0 0);
DISPLAY INVISIBLE (0 0);
FORCEPROP 2 LAST PAGE_BORDER TRUE
J 0
(-7890 5250);
DISPLAY 0.638298 (-7890 5250);
PAINT PINK (-7890 5250);
DISPLAY INVISIBLE (-7890 5250);
FORCEPROP 2 LAST CDS_XR_PAGE_TITLE CR-283 : @T6G_MB_LIB.T6G(SCH_1):PAGE283
J 0
(-7890 5250);
DISPLAY 0.638298 (-7890 5250);
PAINT PINK (-7890 5250);
DISPLAY INVISIBLE (-7890 5250);
FORCEPROP 2 LAST CUSTOM_TXT_CDS <XR_PAGE_TITLE>
J 0
(-7890 5250);
DISPLAY 0.638298 (-7890 5250);
PAINT PINK (-7890 5250);
DISPLAY INVISIBLE (-7890 5250);
FORCEPROP 1 LAST COMMENT_BODY TRUE
J 0
(12 -13);
DISPLAY 0.978723 (12 -13);
PAINT GREEN (12 -13);
DISPLAY INVISIBLE (12 -13);
FORCEPROP 1 LAST Q_DEPT BU9
J 1
(-3763 49);
DISPLAY 1.957447 (-3763 49);
PAINT GREEN (-3763 49);
DISPLAY INVISIBLE (-3763 49);
FORCEPROP 0 LAST CDS_CON_LAST_MODIFIED Thu Aug 24 10:16:10 2023
J 0
(-1885 15);
DISPLAY INVISIBLE (-1885 15);
QUIT
